# BASEBOARD_FAB2 (Tioga Pass) — schematic netlist excerpt (pin names and nets, part order shuffled) for the footprints in the layout excerpt that follows; sources: Cadence DE-HDL packaged netlist, KiCad conversion of Wiwynn_Tioga_Pass_MB.brd

R9M2  RES  2 1.0% CHIP  pkg 0402  page 100 : A = M_K_CPU_VREF ; B = M_K_VREF
C3P16  CAP  0.22UF 16V 10% X7R  pkg 0402  page 107 : A = P3E_CPU0_PE1_SS_TXN<1> ; B = P3E_CPU0_PE1_SS_C_TXN<1>
R2N16  RES  10.0K 1% CHIP  pkg 0402  page 133 : A = P3V3_STBY ; B = PU_IRQ_VRALERT_N

(kicad_pcb
	(version 20260206)
	(generator "pcbnew")
	(generator_version "10.0")
	(general
		(thickness 1.6)
		(legacy_teardrops no)
	)
	(paper "A4")
	(title_block
		(title "Wiwynn_Tioga_Pass_MB.brd")
		(comment 1 "Tioga Pass / footprints 4191-4193 of 4770")
	)
	(layers
		(0 "F.Cu" signal "TOP")
		(4 "In1.Cu" signal "L2GND")
		(6 "In2.Cu" signal "L3")
		(8 "In3.Cu" signal "L4GND")
		(10 "In4.Cu" signal "L5")
		(12 "In5.Cu" signal "L6GND")
		(14 "In6.Cu" signal "L7VCC")
		(16 "In7.Cu" signal "L8VCC")
		(18 "In8.Cu" signal "L9GND")
		(20 "In9.Cu" signal "L10")
		(22 "In10.Cu" signal "L11GND")
		(24 "In11.Cu" signal "L12")
		(26 "In12.Cu" signal "L13GND")
		(2 "B.Cu" signal "BOTTOM")
		(9 "F.Adhes" user "F.Adhesive")
		(11 "B.Adhes" user "B.Adhesive")
		(13 "F.Paste" user "Package Geometry/Pastemask Top")
		(15 "B.Paste" user "Package Geometry/Pastemask Bottom")
		(5 "F.SilkS" user "Ref Des/Silkscreen Top")
		(7 "B.SilkS" user "Ref Des/Silkscreen Bottom")
		(1 "F.Mask" user "Board Geometry/Soldermask Top")
		(3 "B.Mask" user "Board Geometry/Soldermask Bottom")
		(17 "Dwgs.User" user "User.Drawings")
		(19 "Cmts.User" user "User.Comments")
		(21 "Eco1.User" user "User.Eco1")
		(23 "Eco2.User" user "User.Eco2")
		(25 "Edge.Cuts" user "Board Geometry/Outline")
		(27 "Margin" user)
		(31 "F.CrtYd" user "Package Geometry/Place Bound Top")
		(29 "B.CrtYd" user "Package Geometry/Place Bound Bottom")
		(35 "F.Fab" user "Ref Des/Assembly Top")
		(33 "B.Fab" user "Ref Des/Assembly Bottom")
	)
	(footprint ""
		(layer "B.Cu")
		(at 404.5585 -97.155 -90)
		(property "Reference" "R2N16"
			(at 0 0 90)
			(layer "B.SilkS")
			(hide yes)
			(effects
				(font
					(size 1.27 1.27)
				)
				(justify mirror)
			)
		)
		(property "Value" ""
			(at 0 0 90)
			(layer "B.Fab")
			(effects
				(font
					(size 1.27 1.27)
				)
				(justify mirror)
			)
		)
		(duplicate_pad_numbers_are_jumpers no)
		(fp_poly
			(pts
				(xy 0.2794 -0.1016) (xy -0.2794 -0.1016) (xy -0.2794 0.9906) (xy 0.2794 0.9906)
			)
			(stroke
				(width 0)
				(type default)
			)
			(fill no)
			(layer "B.CrtYd")
		)
		(fp_line
			(start -0.2794 0.9906)
			(end -0.2794 -0.1016)
			(stroke
				(width 0.1)
				(type default)
			)
			(layer "B.Fab")
		)
		(fp_line
			(start 0.2794 0.9906)
			(end -0.2794 0.9906)
			(stroke
				(width 0.1)
				(type default)
			)
			(layer "B.Fab")
		)
		(fp_line
			(start -0.2794 -0.1016)
			(end 0.2794 -0.1016)
			(stroke
				(width 0.1)
				(type default)
			)
			(layer "B.Fab")
		)
		(fp_line
			(start 0.2794 -0.1016)
			(end 0.2794 0.9906)
			(stroke
				(width 0.1)
				(type default)
			)
			(layer "B.Fab")
		)
		(pad "1" smd rect
			(at 0 0 90)
			(size 0.508 0.508)
			(layers "B.Cu" "B.Mask" "B.Paste")
			(net "P3V3_STBY")
		)
		(pad "2" smd rect
			(at 0 0.889 90)
			(size 0.508 0.508)
			(layers "B.Cu" "B.Mask" "B.Paste")
			(net "PU_IRQ_VRALERT_N")
		)
		(zone
			(layer "B.Cu")
			(hatch none 0.5)
			(connect_pads
				(clearance 0)
			)
			(min_thickness 0.25)
			(keepout
				(tracks not_allowed)
				(vias allowed)
				(pads allowed)
				(copperpour not_allowed)
				(footprints allowed)
			)
			(placement
				(enabled no)
				(sheetname "")
			)
			(fill
				(thermal_gap 0.5)
				(thermal_bridge_width 0.5)
				(island_removal_mode 0)
			)
			(polygon
				(pts
					(xy 403.9235 -96.901) (xy 403.9235 -97.409) (xy 404.3045 -97.409) (xy 404.3045 -96.901)
				)
			)
		)
		(zone
			(layer "B.Cu")
			(hatch none 0.5)
			(connect_pads
				(clearance 0)
			)
			(min_thickness 0.25)
			(keepout
				(tracks allowed)
				(vias not_allowed)
				(pads allowed)
				(copperpour not_allowed)
				(footprints allowed)
			)
			(placement
				(enabled no)
				(sheetname "")
			)
			(fill
				(thermal_gap 0.5)
				(thermal_bridge_width 0.5)
				(island_removal_mode 0)
			)
			(polygon
				(pts
					(xy 404.3045 -96.901) (xy 404.3045 -97.409) (xy 403.9235 -97.409) (xy 403.9235 -96.901)
				)
			)
		)
	)
	(footprint ""
		(layer "B.Cu")
		(at 27.912568 -134.874 180)
		(property "Reference" "R9M2"
			(at 0 0 0)
			(layer "B.SilkS")
			(hide yes)
			(effects
				(font
					(size 1.27 1.27)
				)
				(justify mirror)
			)
		)
		(property "Value" ""
			(at 0 0 0)
			(layer "B.Fab")
			(effects
				(font
					(size 1.27 1.27)
				)
				(justify mirror)
			)
		)
		(duplicate_pad_numbers_are_jumpers no)
		(fp_poly
			(pts
				(xy 0.2794 -0.1016) (xy -0.2794 -0.1016) (xy -0.2794 0.9906) (xy 0.2794 0.9906)
			)
			(stroke
				(width 0)
				(type default)
			)
			(fill no)
			(layer "B.CrtYd")
		)
		(fp_line
			(start 0.2794 0.9906)
			(end -0.2794 0.9906)
			(stroke
				(width 0.1)
				(type default)
			)
			(layer "B.Fab")
		)
		(fp_line
			(start 0.2794 -0.1016)
			(end 0.2794 0.9906)
			(stroke
				(width 0.1)
				(type default)
			)
			(layer "B.Fab")
		)
		(fp_line
			(start -0.2794 0.9906)
			(end -0.2794 -0.1016)
			(stroke
				(width 0.1)
				(type default)
			)
			(layer "B.Fab")
		)
		(fp_line
			(start -0.2794 -0.1016)
			(end 0.2794 -0.1016)
			(stroke
				(width 0.1)
				(type default)
			)
			(layer "B.Fab")
		)
		(pad "1" smd rect
			(at 0 0)
			(size 0.508 0.508)
			(layers "B.Cu" "B.Mask" "B.Paste")
			(net "M_K_CPU_VREF")
		)
		(pad "2" smd rect
			(at 0 0.889)
			(size 0.508 0.508)
			(layers "B.Cu" "B.Mask" "B.Paste")
			(net "M_K_VREF")
		)
		(zone
			(layer "B.Cu")
			(hatch none 0.5)
			(connect_pads
				(clearance 0)
			)
			(min_thickness 0.25)
			(keepout
				(tracks not_allowed)
				(vias allowed)
				(pads allowed)
				(copperpour not_allowed)
				(footprints allowed)
			)
			(placement
				(enabled no)
				(sheetname "")
			)
			(fill
				(thermal_gap 0.5)
				(thermal_bridge_width 0.5)
				(island_removal_mode 0)
			)
			(polygon
				(pts
					(xy 27.658568 -135.509) (xy 28.166568 -135.509) (xy 28.166568 -135.128) (xy 27.658568 -135.128)
				)
			)
		)
		(zone
			(layer "B.Cu")
			(hatch none 0.5)
			(connect_pads
				(clearance 0)
			)
			(min_thickness 0.25)
			(keepout
				(tracks allowed)
				(vias not_allowed)
				(pads allowed)
				(copperpour not_allowed)
				(footprints allowed)
			)
			(placement
				(enabled no)
				(sheetname "")
			)
			(fill
				(thermal_gap 0.5)
				(thermal_bridge_width 0.5)
				(island_removal_mode 0)
			)
			(polygon
				(pts
					(xy 27.658568 -135.128) (xy 28.166568 -135.128) (xy 28.166568 -135.509) (xy 27.658568 -135.509)
				)
			)
		)
	)
	(footprint ""
		(layer "B.Cu")
		(at 343.063068 -77.694536)
		(property "Reference" "C3P16"
			(at 0 0 0)
			(layer "B.SilkS")
			(hide yes)
			(effects
				(font
					(size 1.27 1.27)
				)
				(justify mirror)
			)
		)
		(property "Value" ""
			(at 0 0 0)
			(layer "B.Fab")
			(effects
				(font
					(size 1.27 1.27)
				)
				(justify mirror)
			)
		)
		(duplicate_pad_numbers_are_jumpers no)
		(fp_poly
			(pts
				(xy -0.3048 -0.1016) (xy -0.3048 0.9906) (xy 0.3048 0.9906) (xy 0.3048 -0.1016)
			)
			(stroke
				(width 0)
				(type default)
			)
			(fill no)
			(layer "B.CrtYd")
		)
		(fp_line
			(start -0.3048 -0.1016)
			(end 0.3048 -0.1016)
			(stroke
				(width 0.1)
				(type default)
			)
			(layer "B.Fab")
		)
		(fp_line
			(start -0.3048 0.9906)
			(end -0.3048 -0.1016)
			(stroke
				(width 0.1)
				(type default)
			)
			(layer "B.Fab")
		)
		(fp_line
			(start 0.3048 -0.1016)
			(end 0.3048 0.9906)
			(stroke
				(width 0.1)
				(type default)
			)
			(layer "B.Fab")
		)
		(fp_line
			(start 0.3048 0.9906)
			(end -0.3048 0.9906)
			(stroke
				(width 0.1)
				(type default)
			)
			(layer "B.Fab")
		)
		(pad "1" smd rect
			(at 0 0 180)
			(size 0.508 0.508)
			(layers "B.Cu" "B.Mask" "B.Paste")
			(net "P3E_CPU0_PE1_SS_TXN<1>")
		)
		(pad "2" smd rect
			(at 0 0.889 180)
			(size 0.508 0.508)
			(layers "B.Cu" "B.Mask" "B.Paste")
			(net "P3E_CPU0_PE1_SS_C_TXN<1>")
		)
		(zone
			(layer "B.Cu")
			(hatch none 0.5)
			(connect_pads
				(clearance 0)
			)
			(min_thickness 0.25)
			(keepout
				(tracks allowed)
				(vias not_allowed)
				(pads allowed)
				(copperpour not_allowed)
				(footprints allowed)
			)
			(placement
				(enabled no)
				(sheetname "")
			)
			(fill
				(thermal_gap 0.5)
				(thermal_bridge_width 0.5)
				(island_removal_mode 0)
			)
			(polygon
				(pts
					(xy 343.317068 -77.440536) (xy 342.809068 -77.440536) (xy 342.809068 -77.059536) (xy 343.317068 -77.059536)
				)
			)
		)
		(zone
			(layer "B.Cu")
			(hatch none 0.5)
			(connect_pads
				(clearance 0)
			)
			(min_thickness 0.25)
			(keepout
				(tracks not_allowed)
				(vias allowed)
				(pads allowed)
				(copperpour not_allowed)
				(footprints allowed)
			)
			(placement
				(enabled no)
				(sheetname "")
			)
			(fill
				(thermal_gap 0.5)
				(thermal_bridge_width 0.5)
				(island_removal_mode 0)
			)
			(polygon
				(pts
					(xy 343.317068 -77.059536) (xy 342.809068 -77.059536) (xy 342.809068 -77.440536) (xy 343.317068 -77.440536)
				)
			)
		)
	)
)
